FILE_TYPE = CONNECTIVITY;
{Allegro Design Entry HDL 17.2-2016 S081 (4005846) 1/11/2022}
"PAGE_NUMBER" = 47;
0"NC";
1"GND\g";
2"LED_POSTCODE_0_R";
3"LED_POSTCODE_1_R";
4"LED_POSTCODE_1_R1";
5"LED_POSTCODE_4_R1";
6"LED_POSTCODE_3_R1";
7"LED_POSTCODE_2_R1";
8"LED_POSTCODE_0_R1";
9"LED_POSTCODE_7_R1";
10"LED_POSTCODE_6_R1";
11"LED_POSTCODE_5_R1";
12"LED_POSTCODE_7_R";
13"LED_POSTCODE_7";
14"LED_POSTCODE_6_R";
15"LED_POSTCODE_6";
16"LED_POSTCODE_5_R";
17"LED_POSTCODE_5";
18"LED_POSTCODE_4_R";
19"LED_POSTCODE_4";
20"LED_POSTCODE_3_R";
21"LED_POSTCODE_3";
22"LED_POSTCODE_2_R";
23"LED_POSTCODE_2";
24"LED_POSTCODE_1";
25"LED_POSTCODE_0";
%"Q_LED"
"1","(3875,2600)","0","pure_quanta","I10";
;
PACK_TYPE"SMLF"
PART_NUMBER"BERD0034Z07"
MATERIAL"IC"
COLOR"LED_RED"
CDS_LIB"pure_quanta"
MANUF_PN"19-217/R6C-P1Q2/3T"
NEEDS_NO_SIZE"TRUE"
LOCATION"D4"
$SEC"1"
CDS_SEC"1";
"A"
$PN"A"18;
"C"
$PN"C"1;
%"Q_LED"
"1","(3875,2000)","0","pure_quanta","I11";
;
PACK_TYPE"SMLF"
PART_NUMBER"BEGR0278Z00"
MATERIAL"IC"
COLOR"LED_GREEN"
CDS_LIB"pure_quanta"
NEEDS_NO_SIZE"TRUE"
MANUF_PN"19-213/GVC-AMNB/3T"
LOCATION"D2"
$SEC"1"
CDS_SEC"1";
"A"
$PN"A"22;
"C"
$PN"C"1;
%"Q_LED"
"1","(3875,2900)","0","pure_quanta","I12";
;
PACK_TYPE"SMLF"
PART_NUMBER"BERD0034Z07"
MATERIAL"IC"
COLOR"LED_RED"
CDS_LIB"pure_quanta"
MANUF_PN"19-217/R6C-P1Q2/3T"
NEEDS_NO_SIZE"TRUE"
LOCATION"D5"
$SEC"1"
CDS_SEC"1";
"A"
$PN"A"16;
"C"
$PN"C"1;
%"Q_LED"
"1","(3875,2300)","0","pure_quanta","I13";
;
COLOR"LED_GREEN"
PACK_TYPE"SMLF"
PART_NUMBER"BEGR0278Z00"
MATERIAL"IC"
CDS_LIB"pure_quanta"
NEEDS_NO_SIZE"TRUE"
MANUF_PN"19-213/GVC-AMNB/3T"
LOCATION"D3"
$SEC"1"
CDS_SEC"1";
"A"
$PN"A"20;
"C"
$PN"C"1;
%"Q_LED"
"1","(3875,3200)","0","pure_quanta","I14";
;
PART_NUMBER"BERD0034Z07"
PACK_TYPE"SMLF"
MATERIAL"IC"
COLOR"LED_RED"
CDS_LIB"pure_quanta"
MANUF_PN"19-217/R6C-P1Q2/3T"
NEEDS_NO_SIZE"TRUE"
LOCATION"D6"
$SEC"1"
CDS_SEC"1";
"A"
$PN"A"14;
"C"
$PN"C"1;
%"Q_RES"
"1","(2675,3500)","0","pure_quanta","I18";
;
VALUE"750"
TOLERANCE"1%"
WATTAGE"1/16W"
MATERIAL"CHIP"
PACK_TYPE"0402LF"
PART_NUMBER"CS17502FB03"
CDS_LIB"pure_quanta"
LOCATION"R597"
$SEC"1"
CDS_SEC"1";
"B"
$PN"2"12;
"A"
$PN"1"13;
%"Q_RES"
"1","(2675,3200)","0","pure_quanta","I20";
;
VALUE"750"
TOLERANCE"1%"
WATTAGE"1/16W"
MATERIAL"CHIP"
PACK_TYPE"0402LF"
PART_NUMBER"CS17502FB03"
CDS_LIB"pure_quanta"
LOCATION"R598"
$SEC"1"
CDS_SEC"1";
"B"
$PN"2"14;
"A"
$PN"1"15;
%"Q_RES"
"1","(2675,2900)","0","pure_quanta","I23";
;
VALUE"750"
TOLERANCE"1%"
WATTAGE"1/16W"
MATERIAL"CHIP"
PACK_TYPE"0402LF"
PART_NUMBER"CS17502FB03"
CDS_LIB"pure_quanta"
LOCATION"R599"
$SEC"1"
CDS_SEC"1";
"B"
$PN"2"16;
"A"
$PN"1"17;
%"Q_RES"
"1","(2675,2600)","0","pure_quanta","I25";
;
VALUE"750"
TOLERANCE"1%"
WATTAGE"1/16W"
MATERIAL"CHIP"
PACK_TYPE"0402LF"
PART_NUMBER"CS17502FB03"
CDS_LIB"pure_quanta"
LOCATION"R600"
$SEC"1"
CDS_SEC"1";
"B"
$PN"2"18;
"A"
$PN"1"19;
%"Q_RES"
"1","(2675,2300)","0","pure_quanta","I31";
;
VALUE"750"
TOLERANCE"1%"
WATTAGE"1/16W"
MATERIAL"CHIP"
PACK_TYPE"0402LF"
PART_NUMBER"CS17502FB03"
CDS_LIB"pure_quanta"
LOCATION"R601"
$SEC"1"
CDS_SEC"1";
"B"
$PN"2"20;
"A"
$PN"1"21;
%"Q_RES"
"1","(2675,2000)","0","pure_quanta","I33";
;
VALUE"750"
TOLERANCE"1%"
WATTAGE"1/16W"
MATERIAL"CHIP"
PACK_TYPE"0402LF"
PART_NUMBER"CS17502FB03"
CDS_LIB"pure_quanta"
LOCATION"R602"
$SEC"1"
CDS_SEC"1";
"B"
$PN"2"22;
"A"
$PN"1"23;
%"Q_RES"
"1","(2675,1700)","0","pure_quanta","I35";
;
VALUE"750"
TOLERANCE"1%"
WATTAGE"1/16W"
MATERIAL"CHIP"
PACK_TYPE"0402LF"
PART_NUMBER"CS17502FB03"
CDS_LIB"pure_quanta"
LOCATION"R603"
$SEC"1"
CDS_SEC"1";
"B"
$PN"2"3;
"A"
$PN"1"24;
%"Q_RES"
"1","(2675,1400)","0","pure_quanta","I37";
;
VALUE"750"
TOLERANCE"1%"
WATTAGE"1/16W"
MATERIAL"CHIP"
PACK_TYPE"0402LF"
PART_NUMBER"CS17502FB03"
CDS_LIB"pure_quanta"
LOCATION"R604"
$SEC"1"
CDS_SEC"1";
"B"
$PN"2"2;
"A"
$PN"1"25;
%"UNIVERSAL_GND"
"1","(5075,1175)","0","logical_power","I39";
;
CDS_LIB"logical_power"
HDL_POWER"GND";
"A"1;
%"Q_RES"
"1","(1600,3650)","2","pure_quanta","I48";
;
VALUE"0"
TOLERANCE"5%"
WATTAGE"1/16W"
MATERIAL"CHIP"
PACK_TYPE"0402LF"
CDS_LIB"pure_quanta"
PART_NUMBER"CS00002JB13"
LOCATION"R669"
$SEC"1"
CDS_SEC"1";
"B"
$PN"2"9;
"A"
$PN"1"13;
%"Q_LED"
"1","(3875,3500)","0","pure_quanta","I5";
;
PACK_TYPE"SMLF"
PART_NUMBER"BERD0034Z07"
MATERIAL"IC"
COLOR"LED_RED"
NEEDS_NO_SIZE"TRUE"
MANUF_PN"19-217/R6C-P1Q2/3T"
CDS_LIB"pure_quanta"
LOCATION"D7"
$SEC"1"
CDS_SEC"1";
"A"
$PN"A"12;
"C"
$PN"C"1;
%"Q_RES"
"1","(1600,3350)","2","pure_quanta","I50";
;
VALUE"0"
TOLERANCE"5%"
WATTAGE"1/16W"
MATERIAL"CHIP"
PACK_TYPE"0402LF"
CDS_LIB"pure_quanta"
PART_NUMBER"CS00002JB13"
LOCATION"R674"
$SEC"1"
CDS_SEC"1";
"B"
$PN"2"10;
"A"
$PN"1"15;
%"Q_RES"
"1","(1600,3050)","2","pure_quanta","I52";
;
VALUE"0"
TOLERANCE"5%"
WATTAGE"1/16W"
MATERIAL"CHIP"
PACK_TYPE"0402LF"
CDS_LIB"pure_quanta"
PART_NUMBER"CS00002JB13"
LOCATION"R676"
$SEC"1"
CDS_SEC"1";
"B"
$PN"2"11;
"A"
$PN"1"17;
%"Q_RES"
"1","(1600,2750)","2","pure_quanta","I54";
;
VALUE"0"
TOLERANCE"5%"
WATTAGE"1/16W"
MATERIAL"CHIP"
PACK_TYPE"0402LF"
CDS_LIB"pure_quanta"
PART_NUMBER"CS00002JB13"
LOCATION"R695"
$SEC"1"
CDS_SEC"1";
"B"
$PN"2"5;
"A"
$PN"1"19;
%"Q_RES"
"1","(1600,2450)","2","pure_quanta","I56";
;
VALUE"0"
TOLERANCE"5%"
WATTAGE"1/16W"
MATERIAL"CHIP"
PACK_TYPE"0402LF"
CDS_LIB"pure_quanta"
PART_NUMBER"CS00002JB13"
LOCATION"R696"
$SEC"1"
CDS_SEC"1";
"B"
$PN"2"6;
"A"
$PN"1"21;
%"Q_RES"
"1","(1600,2150)","2","pure_quanta","I58";
;
VALUE"0"
TOLERANCE"5%"
WATTAGE"1/16W"
MATERIAL"CHIP"
PACK_TYPE"0402LF"
CDS_LIB"pure_quanta"
PART_NUMBER"CS00002JB13"
LOCATION"R697"
$SEC"1"
CDS_SEC"1";
"B"
$PN"2"7;
"A"
$PN"1"23;
%"Q_RES"
"1","(1600,1850)","2","pure_quanta","I60";
;
VALUE"0"
TOLERANCE"5%"
MATERIAL"CHIP"
WATTAGE"1/16W"
PACK_TYPE"0402LF"
CDS_LIB"pure_quanta"
PART_NUMBER"CS00002JB13"
LOCATION"R698"
$SEC"1"
CDS_SEC"1";
"B"
$PN"2"4;
"A"
$PN"1"24;
%"Q_RES"
"1","(1600,1550)","2","pure_quanta","I62";
;
VALUE"0"
TOLERANCE"5%"
WATTAGE"1/16W"
MATERIAL"CHIP"
PACK_TYPE"0402LF"
CDS_LIB"pure_quanta"
PART_NUMBER"CS00002JB13"
LOCATION"R700"
$SEC"1"
CDS_SEC"1";
"B"
$PN"2"8;
"A"
$PN"1"25;
%"Q_LED"
"1","(3875,1400)","0","pure_quanta","I7";
;
PACK_TYPE"SMLF"
MATERIAL"IC"
COLOR"LED_GREEN"
PART_NUMBER"BEGR0278Z00"
CDS_LIB"pure_quanta"
NEEDS_NO_SIZE"TRUE"
MANUF_PN"19-213/GVC-AMNB/3T"
LOCATION"D0"
$SEC"1"
CDS_SEC"1";
"A"
$PN"A"2;
"C"
$PN"C"1;
%"Q_LED"
"1","(3875,1700)","0","pure_quanta","I9";
;
PACK_TYPE"SMLF"
MATERIAL"IC"
PART_NUMBER"BEGR0278Z00"
COLOR"LED_GREEN"
CDS_LIB"pure_quanta"
NEEDS_NO_SIZE"TRUE"
MANUF_PN"19-213/GVC-AMNB/3T"
LOCATION"D1"
$SEC"1"
CDS_SEC"1";
"A"
$PN"A"3;
"C"
$PN"C"1;
END.
